# S9S_MB_2U (Grand Teton) — schematic netlist excerpt (pin names and nets, part order shuffled) for the footprints in the layout excerpt that follows; sources: Cadence DE-HDL packaged netlist, KiCad conversion of 03242023_DA0F0TMBIJ0_F0T_Motherboard_J_brd_V01_OCP.brd

R4701  Q_RES  4.7K 5% CHIP  pkg 0402LF  page 245 : A = P3V3_AUX ; B = FM_FAN_PWR_EN
PC521_P1_6  Q_CAP  22UF 4V 20% X6S  pkg C0805  page 287 : A = PVCCIN_CPU1 ; B = GND
PC283_P0_3  Q_CAP  22UF 16V 20% X6S  pkg C0805  page 268 : A = SW_P12V_PVCCIN_CPU0_FLT ; B = GND

(kicad_pcb
	(version 20260206)
	(generator "pcbnew")
	(generator_version "10.0")
	(general
		(thickness 1.6)
		(legacy_teardrops no)
	)
	(paper "A4")
	(title_block
		(title "03242023_DA0F0TMBIJ0_F0T_Motherboard_J_brd_V01_OCP.brd")
		(comment 1 "Grand Teton / footprints 5333-5335 of 6105")
	)
	(layers
		(0 "F.Cu" signal "TOP")
		(4 "In1.Cu" signal "GND")
		(6 "In2.Cu" signal "IN1")
		(8 "In3.Cu" signal "GND1")
		(10 "In4.Cu" signal "IN2")
		(12 "In5.Cu" signal "GND2")
		(14 "In6.Cu" signal "IN3")
		(16 "In7.Cu" signal "GND3")
		(18 "In8.Cu" signal "VCC")
		(20 "In9.Cu" signal "VCC1")
		(22 "In10.Cu" signal "GND4")
		(24 "In11.Cu" signal "IN4")
		(26 "In12.Cu" signal "GND5")
		(28 "In13.Cu" signal "IN5")
		(30 "In14.Cu" signal "GND6")
		(32 "In15.Cu" signal "IN6")
		(34 "In16.Cu" signal "GND7")
		(2 "B.Cu" signal "BOTTOM")
		(9 "F.Adhes" user "F.Adhesive")
		(11 "B.Adhes" user "B.Adhesive")
		(13 "F.Paste" user "Package Geometry/Pastemask Top")
		(15 "B.Paste" user "Package Geometry/Pastemask Bottom")
		(5 "F.SilkS" user "Ref Des/Silkscreen Top")
		(7 "B.SilkS" user "Ref Des/Silkscreen Bottom")
		(1 "F.Mask" user "Board Geometry/Soldermask Top")
		(3 "B.Mask" user "Board Geometry/Soldermask Bottom")
		(17 "Dwgs.User" user "User.Drawings")
		(19 "Cmts.User" user "User.Comments")
		(21 "Eco1.User" user "User.Eco1")
		(23 "Eco2.User" user "User.Eco2")
		(25 "Edge.Cuts" user "Board Geometry/Outline")
		(27 "Margin" user)
		(31 "F.CrtYd" user "Package Geometry/Place Bound Top")
		(29 "B.CrtYd" user "Package Geometry/Place Bound Bottom")
		(35 "F.Fab" user "Ref Des/Assembly Top")
		(33 "B.Fab" user "Ref Des/Assembly Bottom")
	)
	(footprint ""
		(layer "B.Cu")
		(at 364.5154 -333.73568 90)
		(property "Reference" "PC283_P0_3"
			(at 0 0 90)
			(layer "B.SilkS")
			(hide yes)
			(effects
				(font
					(size 1.27 1.27)
				)
				(justify mirror)
			)
		)
		(property "Value" ""
			(at 0 0 90)
			(layer "B.Fab")
			(effects
				(font
					(size 1.27 1.27)
				)
				(justify mirror)
			)
		)
		(duplicate_pad_numbers_are_jumpers no)
		(fp_line
			(start 1.524 -0.762)
			(end -1.524 -0.762)
			(stroke
				(width 0.1524)
				(type default)
			)
			(layer "B.SilkS")
		)
		(fp_line
			(start -1.524 -0.762)
			(end -1.524 0.762)
			(stroke
				(width 0.1524)
				(type default)
			)
			(layer "B.SilkS")
		)
		(fp_line
			(start 1.524 0.762)
			(end 1.524 -0.762)
			(stroke
				(width 0.1524)
				(type default)
			)
			(layer "B.SilkS")
		)
		(fp_line
			(start -1.524 0.762)
			(end 1.524 0.762)
			(stroke
				(width 0.1524)
				(type default)
			)
			(layer "B.SilkS")
		)
		(fp_line
			(start 1.1049 -0.724916)
			(end 1.1049 0.724916)
			(stroke
				(width 0.1)
				(type default)
			)
			(layer "B.Fab")
		)
		(fp_line
			(start -1.1049 -0.724916)
			(end 1.1049 -0.724916)
			(stroke
				(width 0.1)
				(type default)
			)
			(layer "B.Fab")
		)
		(fp_line
			(start 1.1049 0.724916)
			(end -1.1049 0.724916)
			(stroke
				(width 0.1)
				(type default)
			)
			(layer "B.Fab")
		)
		(fp_line
			(start -1.1049 0.724916)
			(end -1.1049 -0.724916)
			(stroke
				(width 0.1)
				(type default)
			)
			(layer "B.Fab")
		)
		(pad "1" smd rect
			(at 0.889 0 90)
			(size 1.016 1.27)
			(layers "B.Cu" "B.Mask" "B.Paste")
			(net "SW_P12V_PVCCIN_CPU0_FLT")
		)
		(pad "2" smd rect
			(at -0.889 0 90)
			(size 1.016 1.27)
			(layers "B.Cu" "B.Mask" "B.Paste")
			(net "GND")
		)
	)
	(footprint ""
		(layer "B.Cu")
		(at 242.2906 -422.9862 90)
		(property "Reference" "R4701"
			(at 0 0 90)
			(layer "B.SilkS")
			(hide yes)
			(effects
				(font
					(size 1.27 1.27)
				)
				(justify mirror)
			)
		)
		(property "Value" ""
			(at 0 0 90)
			(layer "B.Fab")
			(effects
				(font
					(size 1.27 1.27)
				)
				(justify mirror)
			)
		)
		(duplicate_pad_numbers_are_jumpers no)
		(fp_line
			(start 0.7874 -0.4064)
			(end -0.7874 -0.4064)
			(stroke
				(width 0.1524)
				(type default)
			)
			(layer "B.SilkS")
		)
		(fp_line
			(start -0.7874 -0.4064)
			(end -0.7874 0.4064)
			(stroke
				(width 0.1524)
				(type default)
			)
			(layer "B.SilkS")
		)
		(fp_line
			(start 0.7874 0.4064)
			(end 0.7874 -0.4064)
			(stroke
				(width 0.1524)
				(type default)
			)
			(layer "B.SilkS")
		)
		(fp_line
			(start -0.7874 0.4064)
			(end 0.7874 0.4064)
			(stroke
				(width 0.1524)
				(type default)
			)
			(layer "B.SilkS")
		)
		(fp_line
			(start 0.67945 -0.305054)
			(end 0.12065 -0.305054)
			(stroke
				(width 0.1)
				(type default)
			)
			(layer "B.Fab")
		)
		(fp_line
			(start 0.12065 -0.305054)
			(end 0.12065 -0.2794)
			(stroke
				(width 0.1)
				(type default)
			)
			(layer "B.Fab")
		)
		(fp_line
			(start -0.12065 -0.3048)
			(end -0.67945 -0.3048)
			(stroke
				(width 0.1)
				(type default)
			)
			(layer "B.Fab")
		)
		(fp_line
			(start -0.67945 -0.3048)
			(end -0.67945 0.3048)
			(stroke
				(width 0.1)
				(type default)
			)
			(layer "B.Fab")
		)
		(fp_line
			(start 0.12065 -0.2794)
			(end -0.12065 -0.2794)
			(stroke
				(width 0.1)
				(type default)
			)
			(layer "B.Fab")
		)
		(fp_line
			(start -0.12065 -0.2794)
			(end -0.12065 -0.3048)
			(stroke
				(width 0.1)
				(type default)
			)
			(layer "B.Fab")
		)
		(fp_line
			(start 0.12065 0.2794)
			(end 0.12065 0.3048)
			(stroke
				(width 0.1)
				(type default)
			)
			(layer "B.Fab")
		)
		(fp_line
			(start -0.120396 0.2794)
			(end 0.12065 0.2794)
			(stroke
				(width 0.1)
				(type default)
			)
			(layer "B.Fab")
		)
		(fp_line
			(start 0.67945 0.3048)
			(end 0.67945 -0.305054)
			(stroke
				(width 0.1)
				(type default)
			)
			(layer "B.Fab")
		)
		(fp_line
			(start 0.12065 0.3048)
			(end 0.67945 0.3048)
			(stroke
				(width 0.1)
				(type default)
			)
			(layer "B.Fab")
		)
		(fp_line
			(start -0.120396 0.3048)
			(end -0.120396 0.2794)
			(stroke
				(width 0.1)
				(type default)
			)
			(layer "B.Fab")
		)
		(fp_line
			(start -0.67945 0.3048)
			(end -0.120396 0.3048)
			(stroke
				(width 0.1)
				(type default)
			)
			(layer "B.Fab")
		)
		(pad "1" smd circle
			(at 0.40005 0 270)
			(size 0 0)
			(layers "B.Cu" "B.Mask" "B.Paste")
			(net "P3V3_AUX")
		)
		(pad "2" smd circle
			(at -0.40005 0 270)
			(size 0 0)
			(layers "B.Cu" "B.Mask" "B.Paste")
			(net "FM_FAN_PWR_EN")
		)
	)
	(footprint ""
		(layer "B.Cu")
		(at 92.333572 -328.298048 -90)
		(property "Reference" "PC521_P1_6"
			(at 0 0 90)
			(layer "B.SilkS")
			(hide yes)
			(effects
				(font
					(size 1.27 1.27)
				)
				(justify mirror)
			)
		)
		(property "Value" ""
			(at 0 0 90)
			(layer "B.Fab")
			(effects
				(font
					(size 1.27 1.27)
				)
				(justify mirror)
			)
		)
		(duplicate_pad_numbers_are_jumpers no)
		(fp_line
			(start -1.524 0.762)
			(end 1.524 0.762)
			(stroke
				(width 0.1524)
				(type default)
			)
			(layer "B.SilkS")
		)
		(fp_line
			(start 1.524 0.762)
			(end 1.524 -0.762)
			(stroke
				(width 0.1524)
				(type default)
			)
			(layer "B.SilkS")
		)
		(fp_line
			(start -1.524 -0.762)
			(end -1.524 0.762)
			(stroke
				(width 0.1524)
				(type default)
			)
			(layer "B.SilkS")
		)
		(fp_line
			(start 1.524 -0.762)
			(end -1.524 -0.762)
			(stroke
				(width 0.1524)
				(type default)
			)
			(layer "B.SilkS")
		)
		(fp_line
			(start -1.1049 0.724916)
			(end -1.1049 -0.724916)
			(stroke
				(width 0.1)
				(type default)
			)
			(layer "B.Fab")
		)
		(fp_line
			(start 1.1049 0.724916)
			(end -1.1049 0.724916)
			(stroke
				(width 0.1)
				(type default)
			)
			(layer "B.Fab")
		)
		(fp_line
			(start -1.1049 -0.724916)
			(end 1.1049 -0.724916)
			(stroke
				(width 0.1)
				(type default)
			)
			(layer "B.Fab")
		)
		(fp_line
			(start 1.1049 -0.724916)
			(end 1.1049 0.724916)
			(stroke
				(width 0.1)
				(type default)
			)
			(layer "B.Fab")
		)
		(pad "1" smd rect
			(at 0.889 0 270)
			(size 1.016 1.27)
			(layers "B.Cu" "B.Mask" "B.Paste")
			(net "PVCCIN_CPU1")
		)
		(pad "2" smd rect
			(at -0.889 0 270)
			(size 1.016 1.27)
			(layers "B.Cu" "B.Mask" "B.Paste")
			(net "GND")
		)
	)
)
